(kicad_pcb
	(version 20260206)
	(generator "pcbnew")
	(generator_version "10.0")
	(general
		(thickness 1.6)
		(legacy_teardrops no)
	)
	(paper "A4")
	(title_block
		(title "panther-plus-userver — 13130-1b_20150205.brd")
		(comment 1 "Honey Badger (Wiwynn) / footprint 894 of 1509 (DIMM1), pads 135-141 of 210")
	)
	(layers
		(0 "F.Cu" signal "TOP")
		(4 "In1.Cu" signal "L2")
		(6 "In2.Cu" signal "L3")
		(8 "In3.Cu" signal "L4")
		(10 "In4.Cu" signal "L5")
		(12 "In5.Cu" signal "L6")
		(14 "In6.Cu" signal "L7")
		(16 "In7.Cu" signal "L8")
		(18 "In8.Cu" signal "L9")
		(20 "In9.Cu" signal "L10")
		(22 "In10.Cu" signal "L11")
		(2 "B.Cu" signal "BOTTOM")
		(9 "F.Adhes" user "F.Adhesive")
		(11 "B.Adhes" user "B.Adhesive")
		(13 "F.Paste" user "Package Geometry/Pastemask Top")
		(15 "B.Paste" user "Package Geometry/Pastemask Bottom")
		(5 "F.SilkS" user "Ref Des/Silkscreen Top")
		(7 "B.SilkS" user "Ref Des/Silkscreen Bottom")
		(1 "F.Mask" user "Board Geometry/Soldermask Top")
		(3 "B.Mask" user "Board Geometry/Soldermask Bottom")
		(17 "Dwgs.User" user "User.Drawings")
		(19 "Cmts.User" user "User.Comments")
		(21 "Eco1.User" user "User.Eco1")
		(23 "Eco2.User" user "User.Eco2")
		(25 "Edge.Cuts" user "Board Geometry/Outline")
		(27 "Margin" user)
		(31 "F.CrtYd" user "Package Geometry/Place Bound Top")
		(29 "B.CrtYd" user "Package Geometry/Place Bound Bottom")
		(35 "F.Fab" user "Ref Des/Assembly Top")
		(33 "B.Fab" user "Ref Des/Assembly Bottom")
	)
	(footprint ""
		(layer "B.Cu")
		(at 158.500064 -66.699892 180)
		(property "Reference" "DIMM1"
			(at 0 0 0)
			(layer "B.SilkS")
			(hide yes)
			(effects
				(font
					(size 1.27 1.27)
				)
				(justify mirror)
			)
		)
		(property "Value" "DDR3-204P-142-COLAY-1-GP-U"
			(at 41.312338 -16.676878 180)
			(unlocked yes)
			(layer "B.Fab")
			(hide yes)
			(effects
				(font
					(size 1.016 1.016)
					(thickness 0.1524)
				)
				(justify mirror)
			)
		)
		(property "Device Type" "AS0A626-J8R6-7H-COLAY-1"
			(at 41.312338 -18.200878 180)
			(unlocked yes)
			(layer "B.Fab")
			(hide yes)
			(effects
				(font
					(size 1.016 1.016)
					(thickness 0.1524)
				)
				(justify mirror)
			)
		)
		(duplicate_pad_numbers_are_jumpers no)
		(pad "133" smd custom
			(at 10.349992 -4.100068)
			(size 0.1143 0.1143)
			(layers "B.Cu" "B.Mask" "B.Paste")
			(net "M_A_DQ32")
			(options
				(clearance outline)
				(anchor circle)
			)
			(primitives
				(gr_poly
					(pts
						(xy 0 -0.9017) (xy -0.03175 -0.89916) (xy -0.0635 -0.889) (xy -0.09144 -0.87376) (xy -0.11684 -0.85344)
						(xy -0.13716 -0.82804) (xy -0.1524 -0.8001) (xy -0.16256 -0.76835) (xy -0.1651 -0.7366) (xy -0.1651 -0.44958)
						(xy -0.17272 -0.44196) (xy -0.19812 -0.4064) (xy -0.2032 -0.39624) (xy -0.20701 -0.38735) (xy -0.21209 -0.37719)
						(xy -0.2159 -0.36703) (xy -0.21844 -0.35687) (xy -0.22225 -0.34544) (xy -0.22352 -0.33528) (xy -0.22606 -0.32512)
						(xy -0.22733 -0.31369) (xy -0.22733 -0.30353) (xy -0.2286 -0.2921) (xy -0.22733 -0.28067) (xy -0.22733 -0.27051)
						(xy -0.22606 -0.25908) (xy -0.22352 -0.24892) (xy -0.22225 -0.23876) (xy -0.21844 -0.22733) (xy -0.2159 -0.21717)
						(xy -0.21209 -0.20701) (xy -0.20701 -0.19685) (xy -0.2032 -0.18796) (xy -0.19812 -0.1778) (xy -0.17272 -0.14224)
						(xy -0.1651 -0.13462) (xy -0.1651 0.7366) (xy -0.16256 0.76835) (xy -0.1524 0.8001) (xy -0.13716 0.82804)
						(xy -0.11684 0.85344) (xy -0.09144 0.87376) (xy -0.0635 0.889) (xy -0.03175 0.89916) (xy 0 0.9017)
						(xy 0.03175 0.89916) (xy 0.0635 0.889) (xy 0.09144 0.87376) (xy 0.11684 0.85344) (xy 0.13716 0.82804)
						(xy 0.1524 0.8001) (xy 0.16256 0.76835) (xy 0.1651 0.7366) (xy 0.1651 -0.13462) (xy 0.17272 -0.14224)
						(xy 0.19812 -0.1778) (xy 0.2032 -0.18796) (xy 0.20701 -0.19685) (xy 0.21209 -0.20701) (xy 0.2159 -0.21717)
						(xy 0.21844 -0.22733) (xy 0.22225 -0.23876) (xy 0.22352 -0.24892) (xy 0.22606 -0.25908) (xy 0.22733 -0.27051)
						(xy 0.22733 -0.28067) (xy 0.2286 -0.2921) (xy 0.22733 -0.30353) (xy 0.22733 -0.31369) (xy 0.22606 -0.32512)
						(xy 0.22352 -0.33528) (xy 0.22225 -0.34544) (xy 0.21844 -0.35687) (xy 0.2159 -0.36703) (xy 0.21209 -0.37719)
						(xy 0.20701 -0.38735) (xy 0.2032 -0.39624) (xy 0.19812 -0.4064) (xy 0.17272 -0.44196) (xy 0.1651 -0.44958)
						(xy 0.1651 -0.7366) (xy 0.16256 -0.76835) (xy 0.1524 -0.8001) (xy 0.13716 -0.82804) (xy 0.11684 -0.85344)
						(xy 0.09144 -0.87376) (xy 0.0635 -0.889) (xy 0.03175 -0.89916)
					)
					(width 0)
					(fill yes)
				)
			)
		)
		(pad "134" smd custom
			(at 10.649966 4.100068)
			(size 0.1143 0.1143)
			(layers "B.Cu" "B.Mask" "B.Paste")
			(net "M_A_DQ36")
			(options
				(clearance outline)
				(anchor circle)
			)
			(primitives
				(gr_poly
					(pts
						(xy 0 -0.9017) (xy -0.03175 -0.89916) (xy -0.0635 -0.889) (xy -0.09144 -0.87376) (xy -0.11684 -0.85344)
						(xy -0.13716 -0.82804) (xy -0.1524 -0.8001) (xy -0.16256 -0.76835) (xy -0.1651 -0.7366) (xy -0.1651 0.13462)
						(xy -0.17272 0.14224) (xy -0.19812 0.1778) (xy -0.2032 0.18796) (xy -0.20701 0.19685) (xy -0.21209 0.20701)
						(xy -0.2159 0.21717) (xy -0.21844 0.22733) (xy -0.22225 0.23876) (xy -0.22352 0.24892) (xy -0.22606 0.25908)
						(xy -0.22733 0.27051) (xy -0.22733 0.28067) (xy -0.2286 0.2921) (xy -0.22733 0.30353) (xy -0.22733 0.31369)
						(xy -0.22606 0.32512) (xy -0.22352 0.33528) (xy -0.22225 0.34544) (xy -0.21844 0.35687) (xy -0.2159 0.36703)
						(xy -0.21209 0.37719) (xy -0.20701 0.38735) (xy -0.2032 0.39624) (xy -0.19812 0.4064) (xy -0.17272 0.44196)
						(xy -0.1651 0.44958) (xy -0.1651 0.7366) (xy -0.16256 0.76835) (xy -0.1524 0.8001) (xy -0.13716 0.82804)
						(xy -0.11684 0.85344) (xy -0.09144 0.87376) (xy -0.0635 0.889) (xy -0.03175 0.89916) (xy 0 0.9017)
						(xy 0.03175 0.89916) (xy 0.0635 0.889) (xy 0.09144 0.87376) (xy 0.11684 0.85344) (xy 0.13716 0.82804)
						(xy 0.1524 0.8001) (xy 0.16256 0.76835) (xy 0.1651 0.7366) (xy 0.1651 0.44958) (xy 0.17272 0.44196)
						(xy 0.19812 0.4064) (xy 0.2032 0.39624) (xy 0.20701 0.38735) (xy 0.21209 0.37719) (xy 0.2159 0.36703)
						(xy 0.21844 0.35687) (xy 0.22225 0.34544) (xy 0.22352 0.33528) (xy 0.22606 0.32512) (xy 0.22733 0.31369)
						(xy 0.22733 0.30353) (xy 0.2286 0.2921) (xy 0.22733 0.28067) (xy 0.22733 0.27051) (xy 0.22606 0.25908)
						(xy 0.22352 0.24892) (xy 0.22225 0.23876) (xy 0.21844 0.22733) (xy 0.2159 0.21717) (xy 0.21209 0.20701)
						(xy 0.20701 0.19685) (xy 0.2032 0.18796) (xy 0.19812 0.1778) (xy 0.17272 0.14224) (xy 0.1651 0.13462)
						(xy 0.1651 -0.7366) (xy 0.16256 -0.76835) (xy 0.1524 -0.8001) (xy 0.13716 -0.82804) (xy 0.11684 -0.85344)
						(xy 0.09144 -0.87376) (xy 0.0635 -0.889) (xy 0.03175 -0.89916)
					)
					(width 0)
					(fill yes)
				)
			)
		)
		(pad "135" smd custom
			(at 10.94994 -4.100068)
			(size 0.1143 0.1143)
			(layers "B.Cu" "B.Mask" "B.Paste")
			(net "M_A_DQ33")
			(options
				(clearance outline)
				(anchor circle)
			)
			(primitives
				(gr_poly
					(pts
						(xy 0 -0.9017) (xy -0.03175 -0.89916) (xy -0.0635 -0.889) (xy -0.09144 -0.87376) (xy -0.11684 -0.85344)
						(xy -0.13716 -0.82804) (xy -0.1524 -0.8001) (xy -0.16256 -0.76835) (xy -0.1651 -0.7366) (xy -0.1651 -0.19685)
						(xy -0.17272 -0.18923) (xy -0.17907 -0.18034) (xy -0.18669 -0.17145) (xy -0.19177 -0.16256) (xy -0.19812 -0.15367)
						(xy -0.20828 -0.13335) (xy -0.21971 -0.10287) (xy -0.22225 -0.09271) (xy -0.22479 -0.08128) (xy -0.22606 -0.07112)
						(xy -0.2286 -0.05969) (xy -0.2286 -0.01651) (xy -0.22606 -0.00508) (xy -0.22479 0.00508) (xy -0.22225 0.01651)
						(xy -0.21971 0.02667) (xy -0.20828 0.05715) (xy -0.19812 0.07747) (xy -0.19177 0.08636) (xy -0.18669 0.09525)
						(xy -0.17907 0.10414) (xy -0.17272 0.11303) (xy -0.1651 0.12065) (xy -0.1651 0.7366) (xy -0.16256 0.76835)
						(xy -0.1524 0.8001) (xy -0.13716 0.82804) (xy -0.11684 0.85344) (xy -0.09144 0.87376) (xy -0.0635 0.889)
						(xy -0.03175 0.89916) (xy 0 0.9017) (xy 0.03175 0.89916) (xy 0.0635 0.889) (xy 0.09144 0.87376)
						(xy 0.11684 0.85344) (xy 0.13716 0.82804) (xy 0.1524 0.8001) (xy 0.16256 0.76835) (xy 0.1651 0.7366)
						(xy 0.1651 0.11938) (xy 0.17272 0.11176) (xy 0.19812 0.0762) (xy 0.2032 0.06604) (xy 0.20701 0.05715)
						(xy 0.21209 0.04699) (xy 0.2159 0.03683) (xy 0.21844 0.02667) (xy 0.22225 0.01524) (xy 0.22352 0.00508)
						(xy 0.22606 -0.00508) (xy 0.22733 -0.01651) (xy 0.22733 -0.02667) (xy 0.2286 -0.0381) (xy 0.22733 -0.04953)
						(xy 0.22733 -0.05969) (xy 0.22606 -0.07112) (xy 0.22352 -0.08128) (xy 0.22225 -0.09144) (xy 0.21844 -0.10287)
						(xy 0.2159 -0.11303) (xy 0.21209 -0.12319) (xy 0.20701 -0.13335) (xy 0.2032 -0.14224) (xy 0.19812 -0.1524)
						(xy 0.17272 -0.18796) (xy 0.1651 -0.19558) (xy 0.1651 -0.7366) (xy 0.16256 -0.76835) (xy 0.1524 -0.8001)
						(xy 0.13716 -0.82804) (xy 0.11684 -0.85344) (xy 0.09144 -0.87376) (xy 0.0635 -0.889) (xy 0.03175 -0.89916)
					)
					(width 0)
					(fill yes)
				)
			)
		)
		(pad "136" smd custom
			(at 11.249914 4.100068)
			(size 0.1143 0.1143)
			(layers "B.Cu" "B.Mask" "B.Paste")
			(net "M_A_DQ37")
			(options
				(clearance outline)
				(anchor circle)
			)
			(primitives
				(gr_poly
					(pts
						(xy 0 -0.9017) (xy -0.03175 -0.89916) (xy -0.0635 -0.889) (xy -0.09144 -0.87376) (xy -0.11684 -0.85344)
						(xy -0.13716 -0.82804) (xy -0.1524 -0.8001) (xy -0.16256 -0.76835) (xy -0.1651 -0.7366) (xy -0.1651 -0.11938)
						(xy -0.17272 -0.11176) (xy -0.19812 -0.0762) (xy -0.2032 -0.06604) (xy -0.20701 -0.05715) (xy -0.21209 -0.04699)
						(xy -0.2159 -0.03683) (xy -0.21844 -0.02667) (xy -0.22225 -0.01524) (xy -0.22352 -0.00508) (xy -0.22606 0.00508)
						(xy -0.22733 0.01651) (xy -0.22733 0.02667) (xy -0.2286 0.0381) (xy -0.22733 0.04953) (xy -0.22733 0.05969)
						(xy -0.22606 0.07112) (xy -0.22352 0.08128) (xy -0.22225 0.09144) (xy -0.21844 0.10287) (xy -0.2159 0.11303)
						(xy -0.21209 0.12319) (xy -0.20701 0.13335) (xy -0.2032 0.14224) (xy -0.19812 0.1524) (xy -0.17272 0.18796)
						(xy -0.1651 0.19558) (xy -0.1651 0.7366) (xy -0.16256 0.76835) (xy -0.1524 0.8001) (xy -0.13716 0.82804)
						(xy -0.11684 0.85344) (xy -0.09144 0.87376) (xy -0.0635 0.889) (xy -0.03175 0.89916) (xy 0 0.9017)
						(xy 0.03175 0.89916) (xy 0.0635 0.889) (xy 0.09144 0.87376) (xy 0.11684 0.85344) (xy 0.13716 0.82804)
						(xy 0.1524 0.8001) (xy 0.16256 0.76835) (xy 0.1651 0.7366) (xy 0.1651 0.19685) (xy 0.17272 0.18923)
						(xy 0.17907 0.18034) (xy 0.18669 0.17145) (xy 0.19177 0.16256) (xy 0.19812 0.15367) (xy 0.20828 0.13335)
						(xy 0.21971 0.10287) (xy 0.22225 0.09271) (xy 0.22479 0.08128) (xy 0.22606 0.07112) (xy 0.2286 0.05969)
						(xy 0.2286 0.01651) (xy 0.22606 0.00508) (xy 0.22479 -0.00508) (xy 0.22225 -0.01651) (xy 0.21971 -0.02667)
						(xy 0.20828 -0.05715) (xy 0.19812 -0.07747) (xy 0.19177 -0.08636) (xy 0.18669 -0.09525) (xy 0.17907 -0.10414)
						(xy 0.17272 -0.11303) (xy 0.1651 -0.12065) (xy 0.1651 -0.7366) (xy 0.16256 -0.76835) (xy 0.1524 -0.8001)
						(xy 0.13716 -0.82804) (xy 0.11684 -0.85344) (xy 0.09144 -0.87376) (xy 0.0635 -0.889) (xy 0.03175 -0.89916)
					)
					(width 0)
					(fill yes)
				)
			)
		)
		(pad "137" smd custom
			(at 11.549888 -4.100068)
			(size 0.1143 0.1143)
			(layers "B.Cu" "B.Mask" "B.Paste")
			(net "GND")
			(options
				(clearance outline)
				(anchor circle)
			)
			(primitives
				(gr_poly
					(pts
						(xy 0 -0.9017) (xy -0.03175 -0.89916) (xy -0.0635 -0.889) (xy -0.09144 -0.87376) (xy -0.11684 -0.85344)
						(xy -0.13716 -0.82804) (xy -0.1524 -0.8001) (xy -0.16256 -0.76835) (xy -0.1651 -0.7366) (xy -0.1651 -0.44958)
						(xy -0.17272 -0.44196) (xy -0.19812 -0.4064) (xy -0.2032 -0.39624) (xy -0.20701 -0.38735) (xy -0.21209 -0.37719)
						(xy -0.2159 -0.36703) (xy -0.21844 -0.35687) (xy -0.22225 -0.34544) (xy -0.22352 -0.33528) (xy -0.22606 -0.32512)
						(xy -0.22733 -0.31369) (xy -0.22733 -0.30353) (xy -0.2286 -0.2921) (xy -0.22733 -0.28067) (xy -0.22733 -0.27051)
						(xy -0.22606 -0.25908) (xy -0.22352 -0.24892) (xy -0.22225 -0.23876) (xy -0.21844 -0.22733) (xy -0.2159 -0.21717)
						(xy -0.21209 -0.20701) (xy -0.20701 -0.19685) (xy -0.2032 -0.18796) (xy -0.19812 -0.1778) (xy -0.17272 -0.14224)
						(xy -0.1651 -0.13462) (xy -0.1651 0.7366) (xy -0.16256 0.76835) (xy -0.1524 0.8001) (xy -0.13716 0.82804)
						(xy -0.11684 0.85344) (xy -0.09144 0.87376) (xy -0.0635 0.889) (xy -0.03175 0.89916) (xy 0 0.9017)
						(xy 0.03175 0.89916) (xy 0.0635 0.889) (xy 0.09144 0.87376) (xy 0.11684 0.85344) (xy 0.13716 0.82804)
						(xy 0.1524 0.8001) (xy 0.16256 0.76835) (xy 0.1651 0.7366) (xy 0.1651 -0.13462) (xy 0.17272 -0.14224)
						(xy 0.19812 -0.1778) (xy 0.2032 -0.18796) (xy 0.20701 -0.19685) (xy 0.21209 -0.20701) (xy 0.2159 -0.21717)
						(xy 0.21844 -0.22733) (xy 0.22225 -0.23876) (xy 0.22352 -0.24892) (xy 0.22606 -0.25908) (xy 0.22733 -0.27051)
						(xy 0.22733 -0.28067) (xy 0.2286 -0.2921) (xy 0.22733 -0.30353) (xy 0.22733 -0.31369) (xy 0.22606 -0.32512)
						(xy 0.22352 -0.33528) (xy 0.22225 -0.34544) (xy 0.21844 -0.35687) (xy 0.2159 -0.36703) (xy 0.21209 -0.37719)
						(xy 0.20701 -0.38735) (xy 0.2032 -0.39624) (xy 0.19812 -0.4064) (xy 0.17272 -0.44196) (xy 0.1651 -0.44958)
						(xy 0.1651 -0.7366) (xy 0.16256 -0.76835) (xy 0.1524 -0.8001) (xy 0.13716 -0.82804) (xy 0.11684 -0.85344)
						(xy 0.09144 -0.87376) (xy 0.0635 -0.889) (xy 0.03175 -0.89916)
					)
					(width 0)
					(fill yes)
				)
			)
		)
		(pad "138" smd custom
			(at 11.850116 4.100068)
			(size 0.1143 0.1143)
			(layers "B.Cu" "B.Mask" "B.Paste")
			(net "GND")
			(options
				(clearance outline)
				(anchor circle)
			)
			(primitives
				(gr_poly
					(pts
						(xy 0 -0.9017) (xy -0.03175 -0.89916) (xy -0.0635 -0.889) (xy -0.09144 -0.87376) (xy -0.11684 -0.85344)
						(xy -0.13716 -0.82804) (xy -0.1524 -0.8001) (xy -0.16256 -0.76835) (xy -0.1651 -0.7366) (xy -0.1651 0.13462)
						(xy -0.17272 0.14224) (xy -0.19812 0.1778) (xy -0.2032 0.18796) (xy -0.20701 0.19685) (xy -0.21209 0.20701)
						(xy -0.2159 0.21717) (xy -0.21844 0.22733) (xy -0.22225 0.23876) (xy -0.22352 0.24892) (xy -0.22606 0.25908)
						(xy -0.22733 0.27051) (xy -0.22733 0.28067) (xy -0.2286 0.2921) (xy -0.22733 0.30353) (xy -0.22733 0.31369)
						(xy -0.22606 0.32512) (xy -0.22352 0.33528) (xy -0.22225 0.34544) (xy -0.21844 0.35687) (xy -0.2159 0.36703)
						(xy -0.21209 0.37719) (xy -0.20701 0.38735) (xy -0.2032 0.39624) (xy -0.19812 0.4064) (xy -0.17272 0.44196)
						(xy -0.1651 0.44958) (xy -0.1651 0.7366) (xy -0.16256 0.76835) (xy -0.1524 0.8001) (xy -0.13716 0.82804)
						(xy -0.11684 0.85344) (xy -0.09144 0.87376) (xy -0.0635 0.889) (xy -0.03175 0.89916) (xy 0 0.9017)
						(xy 0.03175 0.89916) (xy 0.0635 0.889) (xy 0.09144 0.87376) (xy 0.11684 0.85344) (xy 0.13716 0.82804)
						(xy 0.1524 0.8001) (xy 0.16256 0.76835) (xy 0.1651 0.7366) (xy 0.1651 0.44958) (xy 0.17272 0.44196)
						(xy 0.19812 0.4064) (xy 0.2032 0.39624) (xy 0.20701 0.38735) (xy 0.21209 0.37719) (xy 0.2159 0.36703)
						(xy 0.21844 0.35687) (xy 0.22225 0.34544) (xy 0.22352 0.33528) (xy 0.22606 0.32512) (xy 0.22733 0.31369)
						(xy 0.22733 0.30353) (xy 0.2286 0.2921) (xy 0.22733 0.28067) (xy 0.22733 0.27051) (xy 0.22606 0.25908)
						(xy 0.22352 0.24892) (xy 0.22225 0.23876) (xy 0.21844 0.22733) (xy 0.2159 0.21717) (xy 0.21209 0.20701)
						(xy 0.20701 0.19685) (xy 0.2032 0.18796) (xy 0.19812 0.1778) (xy 0.17272 0.14224) (xy 0.1651 0.13462)
						(xy 0.1651 -0.7366) (xy 0.16256 -0.76835) (xy 0.1524 -0.8001) (xy 0.13716 -0.82804) (xy 0.11684 -0.85344)
						(xy 0.09144 -0.87376) (xy 0.0635 -0.889) (xy 0.03175 -0.89916)
					)
					(width 0)
					(fill yes)
				)
			)
		)
		(pad "139" smd custom
			(at 12.15009 -4.100068)
			(size 0.1143 0.1143)
			(layers "B.Cu" "B.Mask" "B.Paste")
			(net "M_A_DQS_DN4")
			(options
				(clearance outline)
				(anchor circle)
			)
			(primitives
				(gr_poly
					(pts
						(xy 0 -0.9017) (xy -0.03175 -0.89916) (xy -0.0635 -0.889) (xy -0.09144 -0.87376) (xy -0.11684 -0.85344)
						(xy -0.13716 -0.82804) (xy -0.1524 -0.8001) (xy -0.16256 -0.76835) (xy -0.1651 -0.7366) (xy -0.1651 -0.19685)
						(xy -0.17272 -0.18923) (xy -0.17907 -0.18034) (xy -0.18669 -0.17145) (xy -0.19177 -0.16256) (xy -0.19812 -0.15367)
						(xy -0.20828 -0.13335) (xy -0.21971 -0.10287) (xy -0.22225 -0.09271) (xy -0.22479 -0.08128) (xy -0.22606 -0.07112)
						(xy -0.2286 -0.05969) (xy -0.2286 -0.01651) (xy -0.22606 -0.00508) (xy -0.22479 0.00508) (xy -0.22225 0.01651)
						(xy -0.21971 0.02667) (xy -0.20828 0.05715) (xy -0.19812 0.07747) (xy -0.19177 0.08636) (xy -0.18669 0.09525)
						(xy -0.17907 0.10414) (xy -0.17272 0.11303) (xy -0.1651 0.12065) (xy -0.1651 0.7366) (xy -0.16256 0.76835)
						(xy -0.1524 0.8001) (xy -0.13716 0.82804) (xy -0.11684 0.85344) (xy -0.09144 0.87376) (xy -0.0635 0.889)
						(xy -0.03175 0.89916) (xy 0 0.9017) (xy 0.03175 0.89916) (xy 0.0635 0.889) (xy 0.09144 0.87376)
						(xy 0.11684 0.85344) (xy 0.13716 0.82804) (xy 0.1524 0.8001) (xy 0.16256 0.76835) (xy 0.1651 0.7366)
						(xy 0.1651 0.11938) (xy 0.17272 0.11176) (xy 0.19812 0.0762) (xy 0.2032 0.06604) (xy 0.20701 0.05715)
						(xy 0.21209 0.04699) (xy 0.2159 0.03683) (xy 0.21844 0.02667) (xy 0.22225 0.01524) (xy 0.22352 0.00508)
						(xy 0.22606 -0.00508) (xy 0.22733 -0.01651) (xy 0.22733 -0.02667) (xy 0.2286 -0.0381) (xy 0.22733 -0.04953)
						(xy 0.22733 -0.05969) (xy 0.22606 -0.07112) (xy 0.22352 -0.08128) (xy 0.22225 -0.09144) (xy 0.21844 -0.10287)
						(xy 0.2159 -0.11303) (xy 0.21209 -0.12319) (xy 0.20701 -0.13335) (xy 0.2032 -0.14224) (xy 0.19812 -0.1524)
						(xy 0.17272 -0.18796) (xy 0.1651 -0.19558) (xy 0.1651 -0.7366) (xy 0.16256 -0.76835) (xy 0.1524 -0.8001)
						(xy 0.13716 -0.82804) (xy 0.11684 -0.85344) (xy 0.09144 -0.87376) (xy 0.0635 -0.889) (xy 0.03175 -0.89916)
					)
					(width 0)
					(fill yes)
				)
			)
		)
	)
)
